(kicad_pcb
	(version 20260206)
	(generator "pcbnew")
	(generator_version "10.0")
	(general
		(thickness 1.6)
		(legacy_teardrops no)
	)
	(paper "A4")
	(title_block
		(title "03242023_DA0F0TMBIJ0_F0T_Motherboard_J_brd_V01_OCP.brd")
		(comment 1 "Grand Teton / footprints 810-814 of 6105")
	)
	(layers
		(0 "F.Cu" signal "TOP")
		(4 "In1.Cu" signal "GND")
		(6 "In2.Cu" signal "IN1")
		(8 "In3.Cu" signal "GND1")
		(10 "In4.Cu" signal "IN2")
		(12 "In5.Cu" signal "GND2")
		(14 "In6.Cu" signal "IN3")
		(16 "In7.Cu" signal "GND3")
		(18 "In8.Cu" signal "VCC")
		(20 "In9.Cu" signal "VCC1")
		(22 "In10.Cu" signal "GND4")
		(24 "In11.Cu" signal "IN4")
		(26 "In12.Cu" signal "GND5")
		(28 "In13.Cu" signal "IN5")
		(30 "In14.Cu" signal "GND6")
		(32 "In15.Cu" signal "IN6")
		(34 "In16.Cu" signal "GND7")
		(2 "B.Cu" signal "BOTTOM")
		(9 "F.Adhes" user "F.Adhesive")
		(11 "B.Adhes" user "B.Adhesive")
		(13 "F.Paste" user "Package Geometry/Pastemask Top")
		(15 "B.Paste" user "Package Geometry/Pastemask Bottom")
		(5 "F.SilkS" user "Ref Des/Silkscreen Top")
		(7 "B.SilkS" user "Ref Des/Silkscreen Bottom")
		(1 "F.Mask" user "Board Geometry/Soldermask Top")
		(3 "B.Mask" user "Board Geometry/Soldermask Bottom")
		(17 "Dwgs.User" user "User.Drawings")
		(19 "Cmts.User" user "User.Comments")
		(21 "Eco1.User" user "User.Eco1")
		(23 "Eco2.User" user "User.Eco2")
		(25 "Edge.Cuts" user "Board Geometry/Outline")
		(27 "Margin" user)
		(31 "F.CrtYd" user "Package Geometry/Place Bound Top")
		(29 "B.CrtYd" user "Package Geometry/Place Bound Bottom")
		(35 "F.Fab" user "Ref Des/Assembly Top")
		(33 "B.Fab" user "Ref Des/Assembly Bottom")
	)
	(footprint ""
		(layer "F.Cu")
		(at 146.541236 -66.708528)
		(property "Reference" "C1614"
			(at 0 0 0)
			(layer "F.SilkS")
			(hide yes)
			(effects
				(font
					(size 1.27 1.27)
				)
			)
		)
		(property "Value" ""
			(at 0 0 0)
			(layer "F.Fab")
			(effects
				(font
					(size 1.27 1.27)
				)
			)
		)
		(duplicate_pad_numbers_are_jumpers no)
		(fp_line
			(start -0.7874 -0.4064)
			(end 0.7874 -0.4064)
			(stroke
				(width 0.1524)
				(type default)
			)
			(layer "F.SilkS")
		)
		(fp_line
			(start -0.7874 0.4064)
			(end -0.7874 -0.4064)
			(stroke
				(width 0.1524)
				(type default)
			)
			(layer "F.SilkS")
		)
		(fp_line
			(start 0.7874 -0.4064)
			(end 0.7874 0.4064)
			(stroke
				(width 0.1524)
				(type default)
			)
			(layer "F.SilkS")
		)
		(fp_line
			(start 0.7874 0.4064)
			(end -0.7874 0.4064)
			(stroke
				(width 0.1524)
				(type default)
			)
			(layer "F.SilkS")
		)
		(fp_line
			(start -0.67945 -0.305054)
			(end -0.12065 -0.305054)
			(stroke
				(width 0.1)
				(type default)
			)
			(layer "F.Fab")
		)
		(fp_line
			(start -0.67945 0.3048)
			(end -0.67945 -0.305054)
			(stroke
				(width 0.1)
				(type default)
			)
			(layer "F.Fab")
		)
		(fp_line
			(start -0.12065 -0.305054)
			(end -0.12065 -0.2794)
			(stroke
				(width 0.1)
				(type default)
			)
			(layer "F.Fab")
		)
		(fp_line
			(start -0.12065 -0.2794)
			(end 0.12065 -0.2794)
			(stroke
				(width 0.1)
				(type default)
			)
			(layer "F.Fab")
		)
		(fp_line
			(start -0.12065 0.2794)
			(end -0.12065 0.3048)
			(stroke
				(width 0.1)
				(type default)
			)
			(layer "F.Fab")
		)
		(fp_line
			(start -0.12065 0.3048)
			(end -0.67945 0.3048)
			(stroke
				(width 0.1)
				(type default)
			)
			(layer "F.Fab")
		)
		(fp_line
			(start 0.120396 0.2794)
			(end -0.12065 0.2794)
			(stroke
				(width 0.1)
				(type default)
			)
			(layer "F.Fab")
		)
		(fp_line
			(start 0.120396 0.3048)
			(end 0.120396 0.2794)
			(stroke
				(width 0.1)
				(type default)
			)
			(layer "F.Fab")
		)
		(fp_line
			(start 0.12065 -0.3048)
			(end 0.67945 -0.3048)
			(stroke
				(width 0.1)
				(type default)
			)
			(layer "F.Fab")
		)
		(fp_line
			(start 0.12065 -0.2794)
			(end 0.12065 -0.3048)
			(stroke
				(width 0.1)
				(type default)
			)
			(layer "F.Fab")
		)
		(fp_line
			(start 0.67945 -0.3048)
			(end 0.67945 0.3048)
			(stroke
				(width 0.1)
				(type default)
			)
			(layer "F.Fab")
		)
		(fp_line
			(start 0.67945 0.3048)
			(end 0.120396 0.3048)
			(stroke
				(width 0.1)
				(type default)
			)
			(layer "F.Fab")
		)
		(pad "1" smd circle
			(at -0.40005 0)
			(size 0 0)
			(layers "F.Cu" "F.Mask" "F.Paste")
			(net "P3V3_AUX")
		)
		(pad "2" smd circle
			(at 0.40005 0)
			(size 0 0)
			(layers "F.Cu" "F.Mask" "F.Paste")
			(net "GND")
		)
	)
	(footprint ""
		(layer "F.Cu")
		(at 444.87338 -44.670218)
		(property "Reference" "U236"
			(at -3.71348 -2.052828 0)
			(unlocked yes)
			(layer "F.SilkS")
			(effects
				(font
					(size 0.7874 0.5842)
					(thickness 0.1524)
				)
				(justify left)
			)
		)
		(property "Value" ""
			(at 0 0 0)
			(layer "F.Fab")
			(effects
				(font
					(size 1.27 1.27)
				)
			)
		)
		(duplicate_pad_numbers_are_jumpers no)
		(fp_line
			(start -1.463548 -1.549908)
			(end -0.787908 -1.549908)
			(stroke
				(width 0.1524)
				(type default)
			)
			(layer "F.SilkS")
		)
		(fp_line
			(start -1.463548 1.549908)
			(end -1.463548 -1.549908)
			(stroke
				(width 0.1524)
				(type default)
			)
			(layer "F.SilkS")
		)
		(fp_line
			(start -0.787908 -1.549908)
			(end 0 -0.762)
			(stroke
				(width 0.1524)
				(type default)
			)
			(layer "F.SilkS")
		)
		(fp_line
			(start 0 -0.762)
			(end 0.762 -1.549908)
			(stroke
				(width 0.1524)
				(type default)
			)
			(layer "F.SilkS")
		)
		(fp_line
			(start 0.762 -1.549908)
			(end 1.463548 -1.549908)
			(stroke
				(width 0.1524)
				(type default)
			)
			(layer "F.SilkS")
		)
		(fp_line
			(start 1.463548 -1.549908)
			(end 1.463548 1.549908)
			(stroke
				(width 0.1524)
				(type default)
			)
			(layer "F.SilkS")
		)
		(fp_line
			(start 1.463548 1.549908)
			(end -1.463548 1.549908)
			(stroke
				(width 0.1524)
				(type default)
			)
			(layer "F.SilkS")
		)
		(fp_poly
			(pts
				(xy -2.86004 -1.050036) (xy -3.4798 -0.740156) (xy -3.4798 -1.359916)
			)
			(stroke
				(width 0)
				(type default)
			)
			(fill yes)
			(layer "F.SilkS")
		)
		(fp_line
			(start -1.549908 -1.549908)
			(end 1.549908 -1.549908)
			(stroke
				(width 0.1)
				(type default)
			)
			(layer "F.Fab")
		)
		(fp_line
			(start -1.549908 1.549908)
			(end -1.549908 -1.549908)
			(stroke
				(width 0.1)
				(type default)
			)
			(layer "F.Fab")
		)
		(fp_line
			(start 1.549908 -1.549908)
			(end 1.549908 1.549908)
			(stroke
				(width 0.1)
				(type default)
			)
			(layer "F.Fab")
		)
		(fp_line
			(start 1.549908 1.549908)
			(end -1.549908 1.549908)
			(stroke
				(width 0.1)
				(type default)
			)
			(layer "F.Fab")
		)
		(fp_poly
			(pts
				(xy -3.4798 -1.359916) (xy -2.86004 -1.050036) (xy -3.4798 -0.740156)
			)
			(stroke
				(width 0)
				(type default)
			)
			(fill yes)
			(layer "F.Fab")
		)
		(pad "1" smd rect
			(at -2.175002 -1.050036 90)
			(size 0.6096 1.1684)
			(layers "F.Cu" "F.Mask" "F.Paste")
			(net "P3V3_AUX")
		)
		(pad "2" smd rect
			(at -2.175002 -0.32512 90)
			(size 0.4318 1.1684)
			(layers "F.Cu" "F.Mask" "F.Paste")
			(net "SMB_OCP_SFF_3V3AUX_SCL")
		)
		(pad "3" smd rect
			(at -2.175002 0.32512 90)
			(size 0.4318 1.1684)
			(layers "F.Cu" "F.Mask" "F.Paste")
			(net "SMB_OCP_SFF_3V3AUX_SDA")
		)
		(pad "4" smd rect
			(at -2.175002 1.050036 90)
			(size 0.6096 1.1684)
			(layers "F.Cu" "F.Mask" "F.Paste")
			(net "GND")
		)
		(pad "5" smd rect
			(at 2.175002 1.050036 90)
			(size 0.6096 1.1684)
			(layers "F.Cu" "F.Mask" "F.Paste")
			(net "HP_LVC3_OCP_V3_1_R_EN")
		)
		(pad "6" smd rect
			(at 2.175002 0.32512 90)
			(size 0.4318 1.1684)
			(layers "F.Cu" "F.Mask" "F.Paste")
			(net "SMB_OCP_SFF_3V3AUX_BUF_SDA")
		)
		(pad "7" smd rect
			(at 2.175002 -0.32512 90)
			(size 0.4318 1.1684)
			(layers "F.Cu" "F.Mask" "F.Paste")
			(net "SMB_OCP_SFF_3V3AUX_BUF_SCL")
		)
		(pad "8" smd rect
			(at 2.175002 -1.050036 90)
			(size 0.6096 1.1684)
			(layers "F.Cu" "F.Mask" "F.Paste")
			(net "P3V3_OCP_SFF")
		)
	)
	(footprint ""
		(layer "F.Cu")
		(at 46.350428 -98.824034)
		(property "Reference" "C2042"
			(at 0 0 0)
			(layer "F.SilkS")
			(hide yes)
			(effects
				(font
					(size 1.27 1.27)
				)
			)
		)
		(property "Value" ""
			(at 0 0 0)
			(layer "F.Fab")
			(effects
				(font
					(size 1.27 1.27)
				)
			)
		)
		(duplicate_pad_numbers_are_jumpers no)
		(fp_line
			(start -0.7874 -0.4064)
			(end 0.7874 -0.4064)
			(stroke
				(width 0.1524)
				(type default)
			)
			(layer "F.SilkS")
		)
		(fp_line
			(start -0.7874 0.4064)
			(end -0.7874 -0.4064)
			(stroke
				(width 0.1524)
				(type default)
			)
			(layer "F.SilkS")
		)
		(fp_line
			(start 0.7874 -0.4064)
			(end 0.7874 0.4064)
			(stroke
				(width 0.1524)
				(type default)
			)
			(layer "F.SilkS")
		)
		(fp_line
			(start 0.7874 0.4064)
			(end -0.7874 0.4064)
			(stroke
				(width 0.1524)
				(type default)
			)
			(layer "F.SilkS")
		)
		(fp_line
			(start -0.67945 -0.305054)
			(end -0.12065 -0.305054)
			(stroke
				(width 0.1)
				(type default)
			)
			(layer "F.Fab")
		)
		(fp_line
			(start -0.67945 0.3048)
			(end -0.67945 -0.305054)
			(stroke
				(width 0.1)
				(type default)
			)
			(layer "F.Fab")
		)
		(fp_line
			(start -0.12065 -0.305054)
			(end -0.12065 -0.2794)
			(stroke
				(width 0.1)
				(type default)
			)
			(layer "F.Fab")
		)
		(fp_line
			(start -0.12065 -0.2794)
			(end 0.12065 -0.2794)
			(stroke
				(width 0.1)
				(type default)
			)
			(layer "F.Fab")
		)
		(fp_line
			(start -0.12065 0.2794)
			(end -0.12065 0.3048)
			(stroke
				(width 0.1)
				(type default)
			)
			(layer "F.Fab")
		)
		(fp_line
			(start -0.12065 0.3048)
			(end -0.67945 0.3048)
			(stroke
				(width 0.1)
				(type default)
			)
			(layer "F.Fab")
		)
		(fp_line
			(start 0.120396 0.2794)
			(end -0.12065 0.2794)
			(stroke
				(width 0.1)
				(type default)
			)
			(layer "F.Fab")
		)
		(fp_line
			(start 0.120396 0.3048)
			(end 0.120396 0.2794)
			(stroke
				(width 0.1)
				(type default)
			)
			(layer "F.Fab")
		)
		(fp_line
			(start 0.12065 -0.3048)
			(end 0.67945 -0.3048)
			(stroke
				(width 0.1)
				(type default)
			)
			(layer "F.Fab")
		)
		(fp_line
			(start 0.12065 -0.2794)
			(end 0.12065 -0.3048)
			(stroke
				(width 0.1)
				(type default)
			)
			(layer "F.Fab")
		)
		(fp_line
			(start 0.67945 -0.3048)
			(end 0.67945 0.3048)
			(stroke
				(width 0.1)
				(type default)
			)
			(layer "F.Fab")
		)
		(fp_line
			(start 0.67945 0.3048)
			(end 0.120396 0.3048)
			(stroke
				(width 0.1)
				(type default)
			)
			(layer "F.Fab")
		)
		(pad "1" smd circle
			(at -0.40005 0)
			(size 0 0)
			(layers "F.Cu" "F.Mask" "F.Paste")
			(net "P3V3_AUX_ADC_MAM")
		)
		(pad "2" smd circle
			(at 0.40005 0)
			(size 0 0)
			(layers "F.Cu" "F.Mask" "F.Paste")
			(net "GND")
		)
	)
	(footprint ""
		(layer "F.Cu")
		(at 11.895836 -92.687648 -90)
		(property "Reference" "C2041"
			(at 0 0 270)
			(layer "F.SilkS")
			(hide yes)
			(effects
				(font
					(size 1.27 1.27)
				)
			)
		)
		(property "Value" ""
			(at 0 0 270)
			(layer "F.Fab")
			(effects
				(font
					(size 1.27 1.27)
				)
			)
		)
		(duplicate_pad_numbers_are_jumpers no)
		(fp_line
			(start -0.7874 0.4064)
			(end -0.7874 -0.4064)
			(stroke
				(width 0.1524)
				(type default)
			)
			(layer "F.SilkS")
		)
		(fp_line
			(start 0.7874 0.4064)
			(end -0.7874 0.4064)
			(stroke
				(width 0.1524)
				(type default)
			)
			(layer "F.SilkS")
		)
		(fp_line
			(start -0.7874 -0.4064)
			(end 0.7874 -0.4064)
			(stroke
				(width 0.1524)
				(type default)
			)
			(layer "F.SilkS")
		)
		(fp_line
			(start 0.7874 -0.4064)
			(end 0.7874 0.4064)
			(stroke
				(width 0.1524)
				(type default)
			)
			(layer "F.SilkS")
		)
		(fp_line
			(start -0.67945 0.3048)
			(end -0.67945 -0.305054)
			(stroke
				(width 0.1)
				(type default)
			)
			(layer "F.Fab")
		)
		(fp_line
			(start -0.12065 0.3048)
			(end -0.67945 0.3048)
			(stroke
				(width 0.1)
				(type default)
			)
			(layer "F.Fab")
		)
		(fp_line
			(start 0.120396 0.3048)
			(end 0.120396 0.2794)
			(stroke
				(width 0.1)
				(type default)
			)
			(layer "F.Fab")
		)
		(fp_line
			(start 0.67945 0.3048)
			(end 0.120396 0.3048)
			(stroke
				(width 0.1)
				(type default)
			)
			(layer "F.Fab")
		)
		(fp_line
			(start -0.12065 0.2794)
			(end -0.12065 0.3048)
			(stroke
				(width 0.1)
				(type default)
			)
			(layer "F.Fab")
		)
		(fp_line
			(start 0.120396 0.2794)
			(end -0.12065 0.2794)
			(stroke
				(width 0.1)
				(type default)
			)
			(layer "F.Fab")
		)
		(fp_line
			(start -0.12065 -0.2794)
			(end 0.12065 -0.2794)
			(stroke
				(width 0.1)
				(type default)
			)
			(layer "F.Fab")
		)
		(fp_line
			(start 0.12065 -0.2794)
			(end 0.12065 -0.3048)
			(stroke
				(width 0.1)
				(type default)
			)
			(layer "F.Fab")
		)
		(fp_line
			(start 0.12065 -0.3048)
			(end 0.67945 -0.3048)
			(stroke
				(width 0.1)
				(type default)
			)
			(layer "F.Fab")
		)
		(fp_line
			(start 0.67945 -0.3048)
			(end 0.67945 0.3048)
			(stroke
				(width 0.1)
				(type default)
			)
			(layer "F.Fab")
		)
		(fp_line
			(start -0.67945 -0.305054)
			(end -0.12065 -0.305054)
			(stroke
				(width 0.1)
				(type default)
			)
			(layer "F.Fab")
		)
		(fp_line
			(start -0.12065 -0.305054)
			(end -0.12065 -0.2794)
			(stroke
				(width 0.1)
				(type default)
			)
			(layer "F.Fab")
		)
		(pad "1" smd circle
			(at -0.40005 0 270)
			(size 0 0)
			(layers "F.Cu" "F.Mask" "F.Paste")
			(net "RST_USB_HUB_R_N")
		)
		(pad "2" smd circle
			(at 0.40005 0 270)
			(size 0 0)
			(layers "F.Cu" "F.Mask" "F.Paste")
			(net "GND")
		)
	)
	(footprint ""
		(layer "F.Cu")
		(at 434.448204 -103.927402 -90)
		(property "Reference" "PC2089"
			(at 0 0 270)
			(layer "F.SilkS")
			(hide yes)
			(effects
				(font
					(size 1.27 1.27)
				)
			)
		)
		(property "Value" ""
			(at 0 0 270)
			(layer "F.Fab")
			(effects
				(font
					(size 1.27 1.27)
				)
			)
		)
		(duplicate_pad_numbers_are_jumpers no)
		(fp_line
			(start -0.7874 0.4064)
			(end -0.7874 -0.4064)
			(stroke
				(width 0.1524)
				(type default)
			)
			(layer "F.SilkS")
		)
		(fp_line
			(start 0.7874 0.4064)
			(end -0.7874 0.4064)
			(stroke
				(width 0.1524)
				(type default)
			)
			(layer "F.SilkS")
		)
		(fp_line
			(start -0.7874 -0.4064)
			(end 0.7874 -0.4064)
			(stroke
				(width 0.1524)
				(type default)
			)
			(layer "F.SilkS")
		)
		(fp_line
			(start 0.7874 -0.4064)
			(end 0.7874 0.4064)
			(stroke
				(width 0.1524)
				(type default)
			)
			(layer "F.SilkS")
		)
		(fp_line
			(start -0.67945 0.3048)
			(end -0.67945 -0.305054)
			(stroke
				(width 0.1)
				(type default)
			)
			(layer "F.Fab")
		)
		(fp_line
			(start -0.12065 0.3048)
			(end -0.67945 0.3048)
			(stroke
				(width 0.1)
				(type default)
			)
			(layer "F.Fab")
		)
		(fp_line
			(start 0.120396 0.3048)
			(end 0.120396 0.2794)
			(stroke
				(width 0.1)
				(type default)
			)
			(layer "F.Fab")
		)
		(fp_line
			(start 0.67945 0.3048)
			(end 0.120396 0.3048)
			(stroke
				(width 0.1)
				(type default)
			)
			(layer "F.Fab")
		)
		(fp_line
			(start -0.12065 0.2794)
			(end -0.12065 0.3048)
			(stroke
				(width 0.1)
				(type default)
			)
			(layer "F.Fab")
		)
		(fp_line
			(start 0.120396 0.2794)
			(end -0.12065 0.2794)
			(stroke
				(width 0.1)
				(type default)
			)
			(layer "F.Fab")
		)
		(fp_line
			(start -0.12065 -0.2794)
			(end 0.12065 -0.2794)
			(stroke
				(width 0.1)
				(type default)
			)
			(layer "F.Fab")
		)
		(fp_line
			(start 0.12065 -0.2794)
			(end 0.12065 -0.3048)
			(stroke
				(width 0.1)
				(type default)
			)
			(layer "F.Fab")
		)
		(fp_line
			(start 0.12065 -0.3048)
			(end 0.67945 -0.3048)
			(stroke
				(width 0.1)
				(type default)
			)
			(layer "F.Fab")
		)
		(fp_line
			(start 0.67945 -0.3048)
			(end 0.67945 0.3048)
			(stroke
				(width 0.1)
				(type default)
			)
			(layer "F.Fab")
		)
		(fp_line
			(start -0.67945 -0.305054)
			(end -0.12065 -0.305054)
			(stroke
				(width 0.1)
				(type default)
			)
			(layer "F.Fab")
		)
		(fp_line
			(start -0.12065 -0.305054)
			(end -0.12065 -0.2794)
			(stroke
				(width 0.1)
				(type default)
			)
			(layer "F.Fab")
		)
		(pad "1" smd circle
			(at -0.40005 0 270)
			(size 0 0)
			(layers "F.Cu" "F.Mask" "F.Paste")
			(net "P3V3_OCP_GATE_PU202_1")
		)
		(pad "2" smd circle
			(at 0.40005 0 270)
			(size 0 0)
			(layers "F.Cu" "F.Mask" "F.Paste")
			(net "GND")
		)
	)
)
